(kicad_pcb
	(version 20260206)
	(generator "pcbnew")
	(generator_version "10.0")
	(general
		(thickness 1.6)
		(legacy_teardrops no)
	)
	(paper "A4")
	(title_block
		(title "04192023_DAF0TMB3IC0_F0TG_MB_C_brd_V02_OCP.brd")
		(comment 1 "Grand Teton / footprints 5407-5413 of 8354")
	)
	(layers
		(0 "F.Cu" signal "TOP")
		(4 "In1.Cu" signal "GND")
		(6 "In2.Cu" signal "IN1")
		(8 "In3.Cu" signal "GND1")
		(10 "In4.Cu" signal "IN2")
		(12 "In5.Cu" signal "GND2")
		(14 "In6.Cu" signal "IN3")
		(16 "In7.Cu" signal "GND3")
		(18 "In8.Cu" signal "VCC")
		(20 "In9.Cu" signal "VCC1")
		(22 "In10.Cu" signal "GND4")
		(24 "In11.Cu" signal "IN4")
		(26 "In12.Cu" signal "GND5")
		(28 "In13.Cu" signal "IN5")
		(30 "In14.Cu" signal "GND6")
		(32 "In15.Cu" signal "IN6")
		(34 "In16.Cu" signal "GND7")
		(2 "B.Cu" signal "BOTTOM")
		(9 "F.Adhes" user "F.Adhesive")
		(11 "B.Adhes" user "B.Adhesive")
		(13 "F.Paste" user "Package Geometry/Pastemask Top")
		(15 "B.Paste" user "Package Geometry/Pastemask Bottom")
		(5 "F.SilkS" user "Ref Des/Silkscreen Top")
		(7 "B.SilkS" user "Ref Des/Silkscreen Bottom")
		(1 "F.Mask" user "Board Geometry/Soldermask Top")
		(3 "B.Mask" user "Board Geometry/Soldermask Bottom")
		(17 "Dwgs.User" user "User.Drawings")
		(19 "Cmts.User" user "User.Comments")
		(21 "Eco1.User" user "User.Eco1")
		(23 "Eco2.User" user "User.Eco2")
		(25 "Edge.Cuts" user "Board Geometry/Outline")
		(27 "Margin" user)
		(31 "F.CrtYd" user "Package Geometry/Place Bound Top")
		(29 "B.CrtYd" user "Package Geometry/Place Bound Bottom")
		(35 "F.Fab" user "Ref Des/Assembly Top")
		(33 "B.Fab" user "Ref Des/Assembly Bottom")
	)
	(footprint ""
		(layer "B.Cu")
		(at 159.7152 -191.1604 -90)
		(property "Reference" "R542"
			(at 0 0 90)
			(layer "B.SilkS")
			(hide yes)
			(effects
				(font
					(size 1.27 1.27)
				)
				(justify mirror)
			)
		)
		(property "Value" ""
			(at 0 0 90)
			(layer "B.Fab")
			(effects
				(font
					(size 1.27 1.27)
				)
				(justify mirror)
			)
		)
		(duplicate_pad_numbers_are_jumpers no)
		(fp_line
			(start -0.7874 0.4064)
			(end 0.7874 0.4064)
			(stroke
				(width 0.1524)
				(type default)
			)
			(layer "B.SilkS")
		)
		(fp_line
			(start 0.7874 0.4064)
			(end 0.7874 -0.4064)
			(stroke
				(width 0.1524)
				(type default)
			)
			(layer "B.SilkS")
		)
		(fp_line
			(start -0.7874 -0.4064)
			(end -0.7874 0.4064)
			(stroke
				(width 0.1524)
				(type default)
			)
			(layer "B.SilkS")
		)
		(fp_line
			(start 0.7874 -0.4064)
			(end -0.7874 -0.4064)
			(stroke
				(width 0.1524)
				(type default)
			)
			(layer "B.SilkS")
		)
		(fp_line
			(start -0.67945 0.3048)
			(end -0.120396 0.3048)
			(stroke
				(width 0.1)
				(type default)
			)
			(layer "B.Fab")
		)
		(fp_line
			(start -0.120396 0.3048)
			(end -0.120396 0.2794)
			(stroke
				(width 0.1)
				(type default)
			)
			(layer "B.Fab")
		)
		(fp_line
			(start 0.12065 0.3048)
			(end 0.67945 0.3048)
			(stroke
				(width 0.1)
				(type default)
			)
			(layer "B.Fab")
		)
		(fp_line
			(start 0.67945 0.3048)
			(end 0.67945 -0.305054)
			(stroke
				(width 0.1)
				(type default)
			)
			(layer "B.Fab")
		)
		(fp_line
			(start -0.120396 0.2794)
			(end 0.12065 0.2794)
			(stroke
				(width 0.1)
				(type default)
			)
			(layer "B.Fab")
		)
		(fp_line
			(start 0.12065 0.2794)
			(end 0.12065 0.3048)
			(stroke
				(width 0.1)
				(type default)
			)
			(layer "B.Fab")
		)
		(fp_line
			(start -0.12065 -0.2794)
			(end -0.12065 -0.3048)
			(stroke
				(width 0.1)
				(type default)
			)
			(layer "B.Fab")
		)
		(fp_line
			(start 0.12065 -0.2794)
			(end -0.12065 -0.2794)
			(stroke
				(width 0.1)
				(type default)
			)
			(layer "B.Fab")
		)
		(fp_line
			(start -0.67945 -0.3048)
			(end -0.67945 0.3048)
			(stroke
				(width 0.1)
				(type default)
			)
			(layer "B.Fab")
		)
		(fp_line
			(start -0.12065 -0.3048)
			(end -0.67945 -0.3048)
			(stroke
				(width 0.1)
				(type default)
			)
			(layer "B.Fab")
		)
		(fp_line
			(start 0.12065 -0.305054)
			(end 0.12065 -0.2794)
			(stroke
				(width 0.1)
				(type default)
			)
			(layer "B.Fab")
		)
		(fp_line
			(start 0.67945 -0.305054)
			(end 0.12065 -0.305054)
			(stroke
				(width 0.1)
				(type default)
			)
			(layer "B.Fab")
		)
		(pad "1" smd circle
			(at 0.40005 0 90)
			(size 0 0)
			(layers "B.Cu" "B.Mask" "B.Paste")
			(net "PVDD11_S3_P1")
		)
		(pad "2" smd circle
			(at -0.40005 0 90)
			(size 0 0)
			(layers "B.Cu" "B.Mask" "B.Paste")
			(net "I3C_1_SPD_DDRGL_CPU1_R_SCL")
		)
	)
	(footprint ""
		(layer "B.Cu")
		(at 446.644014 -192.660016)
		(property "Reference" "C169"
			(at 0 0 0)
			(layer "B.SilkS")
			(hide yes)
			(effects
				(font
					(size 1.27 1.27)
				)
				(justify mirror)
			)
		)
		(property "Value" ""
			(at 0 0 0)
			(layer "B.Fab")
			(effects
				(font
					(size 1.27 1.27)
				)
				(justify mirror)
			)
		)
		(duplicate_pad_numbers_are_jumpers no)
		(fp_line
			(start -1.524 -0.762)
			(end -1.524 0.762)
			(stroke
				(width 0.1524)
				(type default)
			)
			(layer "B.SilkS")
		)
		(fp_line
			(start -1.524 0.762)
			(end 1.524 0.762)
			(stroke
				(width 0.1524)
				(type default)
			)
			(layer "B.SilkS")
		)
		(fp_line
			(start 1.524 -0.762)
			(end -1.524 -0.762)
			(stroke
				(width 0.1524)
				(type default)
			)
			(layer "B.SilkS")
		)
		(fp_line
			(start 1.524 0.762)
			(end 1.524 -0.762)
			(stroke
				(width 0.1524)
				(type default)
			)
			(layer "B.SilkS")
		)
		(fp_line
			(start -1.1049 -0.724916)
			(end 1.1049 -0.724916)
			(stroke
				(width 0.1)
				(type default)
			)
			(layer "B.Fab")
		)
		(fp_line
			(start -1.1049 0.724916)
			(end -1.1049 -0.724916)
			(stroke
				(width 0.1)
				(type default)
			)
			(layer "B.Fab")
		)
		(fp_line
			(start 1.1049 -0.724916)
			(end 1.1049 0.724916)
			(stroke
				(width 0.1)
				(type default)
			)
			(layer "B.Fab")
		)
		(fp_line
			(start 1.1049 0.724916)
			(end -1.1049 0.724916)
			(stroke
				(width 0.1)
				(type default)
			)
			(layer "B.Fab")
		)
		(pad "1" smd rect
			(at 0.889 0)
			(size 1.016 1.27)
			(layers "B.Cu" "B.Mask" "B.Paste")
			(net "P12V_MEM_CPU0")
		)
		(pad "2" smd rect
			(at -0.889 0)
			(size 1.016 1.27)
			(layers "B.Cu" "B.Mask" "B.Paste")
			(net "GND")
		)
	)
	(footprint ""
		(layer "B.Cu")
		(at 69.30898 -166.26332 90)
		(property "Reference" "PR425"
			(at 0 0 90)
			(layer "B.SilkS")
			(hide yes)
			(effects
				(font
					(size 1.27 1.27)
				)
				(justify mirror)
			)
		)
		(property "Value" ""
			(at 0 0 90)
			(layer "B.Fab")
			(effects
				(font
					(size 1.27 1.27)
				)
				(justify mirror)
			)
		)
		(duplicate_pad_numbers_are_jumpers no)
		(fp_line
			(start 0.7874 -0.4064)
			(end -0.7874 -0.4064)
			(stroke
				(width 0.1524)
				(type default)
			)
			(layer "B.SilkS")
		)
		(fp_line
			(start -0.7874 -0.4064)
			(end -0.7874 0.4064)
			(stroke
				(width 0.1524)
				(type default)
			)
			(layer "B.SilkS")
		)
		(fp_line
			(start 0.7874 0.4064)
			(end 0.7874 -0.4064)
			(stroke
				(width 0.1524)
				(type default)
			)
			(layer "B.SilkS")
		)
		(fp_line
			(start -0.7874 0.4064)
			(end 0.7874 0.4064)
			(stroke
				(width 0.1524)
				(type default)
			)
			(layer "B.SilkS")
		)
		(fp_line
			(start 0.67945 -0.305054)
			(end 0.12065 -0.305054)
			(stroke
				(width 0.1)
				(type default)
			)
			(layer "B.Fab")
		)
		(fp_line
			(start 0.12065 -0.305054)
			(end 0.12065 -0.2794)
			(stroke
				(width 0.1)
				(type default)
			)
			(layer "B.Fab")
		)
		(fp_line
			(start -0.12065 -0.3048)
			(end -0.67945 -0.3048)
			(stroke
				(width 0.1)
				(type default)
			)
			(layer "B.Fab")
		)
		(fp_line
			(start -0.67945 -0.3048)
			(end -0.67945 0.3048)
			(stroke
				(width 0.1)
				(type default)
			)
			(layer "B.Fab")
		)
		(fp_line
			(start 0.12065 -0.2794)
			(end -0.12065 -0.2794)
			(stroke
				(width 0.1)
				(type default)
			)
			(layer "B.Fab")
		)
		(fp_line
			(start -0.12065 -0.2794)
			(end -0.12065 -0.3048)
			(stroke
				(width 0.1)
				(type default)
			)
			(layer "B.Fab")
		)
		(fp_line
			(start 0.12065 0.2794)
			(end 0.12065 0.3048)
			(stroke
				(width 0.1)
				(type default)
			)
			(layer "B.Fab")
		)
		(fp_line
			(start -0.120396 0.2794)
			(end 0.12065 0.2794)
			(stroke
				(width 0.1)
				(type default)
			)
			(layer "B.Fab")
		)
		(fp_line
			(start 0.67945 0.3048)
			(end 0.67945 -0.305054)
			(stroke
				(width 0.1)
				(type default)
			)
			(layer "B.Fab")
		)
		(fp_line
			(start 0.12065 0.3048)
			(end 0.67945 0.3048)
			(stroke
				(width 0.1)
				(type default)
			)
			(layer "B.Fab")
		)
		(fp_line
			(start -0.120396 0.3048)
			(end -0.120396 0.2794)
			(stroke
				(width 0.1)
				(type default)
			)
			(layer "B.Fab")
		)
		(fp_line
			(start -0.67945 0.3048)
			(end -0.120396 0.3048)
			(stroke
				(width 0.1)
				(type default)
			)
			(layer "B.Fab")
		)
		(pad "1" smd circle
			(at 0.40005 0 270)
			(size 0 0)
			(layers "B.Cu" "B.Mask" "B.Paste")
			(net "PVDDCR_CPU0_P1_VOS6")
		)
		(pad "2" smd circle
			(at -0.40005 0 270)
			(size 0 0)
			(layers "B.Cu" "B.Mask" "B.Paste")
			(net "PVDDCR_CPU0_P1")
		)
	)
	(footprint ""
		(layer "B.Cu")
		(at 325.861426 -398.455134 180)
		(property "Reference" "C560"
			(at 0 0 0)
			(layer "B.SilkS")
			(hide yes)
			(effects
				(font
					(size 1.27 1.27)
				)
				(justify mirror)
			)
		)
		(property "Value" ""
			(at 0 0 0)
			(layer "B.Fab")
			(effects
				(font
					(size 1.27 1.27)
				)
				(justify mirror)
			)
		)
		(duplicate_pad_numbers_are_jumpers no)
		(fp_line
			(start 1.524 0.762)
			(end 1.524 -0.762)
			(stroke
				(width 0.1524)
				(type default)
			)
			(layer "B.SilkS")
		)
		(fp_line
			(start 1.524 -0.762)
			(end -1.524 -0.762)
			(stroke
				(width 0.1524)
				(type default)
			)
			(layer "B.SilkS")
		)
		(fp_line
			(start -1.524 0.762)
			(end 1.524 0.762)
			(stroke
				(width 0.1524)
				(type default)
			)
			(layer "B.SilkS")
		)
		(fp_line
			(start -1.524 -0.762)
			(end -1.524 0.762)
			(stroke
				(width 0.1524)
				(type default)
			)
			(layer "B.SilkS")
		)
		(fp_line
			(start 1.1049 0.724916)
			(end -1.1049 0.724916)
			(stroke
				(width 0.1)
				(type default)
			)
			(layer "B.Fab")
		)
		(fp_line
			(start 1.1049 -0.724916)
			(end 1.1049 0.724916)
			(stroke
				(width 0.1)
				(type default)
			)
			(layer "B.Fab")
		)
		(fp_line
			(start -1.1049 0.724916)
			(end -1.1049 -0.724916)
			(stroke
				(width 0.1)
				(type default)
			)
			(layer "B.Fab")
		)
		(fp_line
			(start -1.1049 -0.724916)
			(end 1.1049 -0.724916)
			(stroke
				(width 0.1)
				(type default)
			)
			(layer "B.Fab")
		)
		(pad "1" smd rect
			(at 0.889 0 180)
			(size 1.016 1.27)
			(layers "B.Cu" "B.Mask" "B.Paste")
			(net "P0V9_CPU0_RT0_2A")
		)
		(pad "2" smd rect
			(at -0.889 0 180)
			(size 1.016 1.27)
			(layers "B.Cu" "B.Mask" "B.Paste")
			(net "GND")
		)
	)
	(footprint ""
		(layer "B.Cu")
		(at 402.322538 -319.198752)
		(property "Reference" "R5029"
			(at 0 0 0)
			(layer "B.SilkS")
			(hide yes)
			(effects
				(font
					(size 1.27 1.27)
				)
				(justify mirror)
			)
		)
		(property "Value" ""
			(at 0 0 0)
			(layer "B.Fab")
			(effects
				(font
					(size 1.27 1.27)
				)
				(justify mirror)
			)
		)
		(duplicate_pad_numbers_are_jumpers no)
		(fp_line
			(start -0.7874 -0.4064)
			(end -0.7874 0.4064)
			(stroke
				(width 0.1524)
				(type default)
			)
			(layer "B.SilkS")
		)
		(fp_line
			(start -0.7874 0.4064)
			(end 0.7874 0.4064)
			(stroke
				(width 0.1524)
				(type default)
			)
			(layer "B.SilkS")
		)
		(fp_line
			(start 0.7874 -0.4064)
			(end -0.7874 -0.4064)
			(stroke
				(width 0.1524)
				(type default)
			)
			(layer "B.SilkS")
		)
		(fp_line
			(start 0.7874 0.4064)
			(end 0.7874 -0.4064)
			(stroke
				(width 0.1524)
				(type default)
			)
			(layer "B.SilkS")
		)
		(fp_line
			(start -0.67945 -0.3048)
			(end -0.67945 0.3048)
			(stroke
				(width 0.1)
				(type default)
			)
			(layer "B.Fab")
		)
		(fp_line
			(start -0.67945 0.3048)
			(end -0.120396 0.3048)
			(stroke
				(width 0.1)
				(type default)
			)
			(layer "B.Fab")
		)
		(fp_line
			(start -0.12065 -0.3048)
			(end -0.67945 -0.3048)
			(stroke
				(width 0.1)
				(type default)
			)
			(layer "B.Fab")
		)
		(fp_line
			(start -0.12065 -0.2794)
			(end -0.12065 -0.3048)
			(stroke
				(width 0.1)
				(type default)
			)
			(layer "B.Fab")
		)
		(fp_line
			(start -0.120396 0.2794)
			(end 0.12065 0.2794)
			(stroke
				(width 0.1)
				(type default)
			)
			(layer "B.Fab")
		)
		(fp_line
			(start -0.120396 0.3048)
			(end -0.120396 0.2794)
			(stroke
				(width 0.1)
				(type default)
			)
			(layer "B.Fab")
		)
		(fp_line
			(start 0.12065 -0.305054)
			(end 0.12065 -0.2794)
			(stroke
				(width 0.1)
				(type default)
			)
			(layer "B.Fab")
		)
		(fp_line
			(start 0.12065 -0.2794)
			(end -0.12065 -0.2794)
			(stroke
				(width 0.1)
				(type default)
			)
			(layer "B.Fab")
		)
		(fp_line
			(start 0.12065 0.2794)
			(end 0.12065 0.3048)
			(stroke
				(width 0.1)
				(type default)
			)
			(layer "B.Fab")
		)
		(fp_line
			(start 0.12065 0.3048)
			(end 0.67945 0.3048)
			(stroke
				(width 0.1)
				(type default)
			)
			(layer "B.Fab")
		)
		(fp_line
			(start 0.67945 -0.305054)
			(end 0.12065 -0.305054)
			(stroke
				(width 0.1)
				(type default)
			)
			(layer "B.Fab")
		)
		(fp_line
			(start 0.67945 0.3048)
			(end 0.67945 -0.305054)
			(stroke
				(width 0.1)
				(type default)
			)
			(layer "B.Fab")
		)
		(pad "1" smd circle
			(at 0.40005 0 180)
			(size 0 0)
			(layers "B.Cu" "B.Mask" "B.Paste")
			(net "GND")
		)
		(pad "2" smd circle
			(at -0.40005 0 180)
			(size 0 0)
			(layers "B.Cu" "B.Mask" "B.Paste")
			(net "IRQ_TPM_SPI_R_N")
		)
	)
	(footprint ""
		(layer "B.Cu")
		(at 219.61475 -347.604588 180)
		(property "Reference" ""
			(at 0 0 0)
			(layer "B.SilkS")
			(hide yes)
			(effects
				(font
					(size 1.27 1.27)
				)
				(justify mirror)
			)
		)
		(property "Value" ""
			(at 0 0 0)
			(layer "B.Fab")
			(effects
				(font
					(size 1.27 1.27)
				)
				(justify mirror)
			)
		)
		(duplicate_pad_numbers_are_jumpers no)
		(pad "1" smd circle
			(at 0 0)
			(size 0.9906 0.9906)
			(layers "B.Cu" "B.Mask" "B.Paste")
			(net "Net_2232")
		)
		(zone
			(layer "B.Cu")
			(hatch none 0.5)
			(connect_pads
				(clearance 0)
			)
			(min_thickness 0.25)
			(keepout
				(tracks not_allowed)
				(vias allowed)
				(pads allowed)
				(copperpour not_allowed)
				(footprints allowed)
			)
			(placement
				(enabled no)
				(sheetname "")
			)
			(fill
				(thermal_gap 0.5)
				(thermal_bridge_width 0.5)
				(island_removal_mode 0)
			)
			(polygon
				(pts
					(arc
						(start 221.24035 -347.604588)
						(mid 217.98915 -347.604588)
						(end 221.24035 -347.604588)
					)
				)
			)
		)
	)
	(footprint ""
		(layer "B.Cu")
		(at 193.929 -97.119948 90)
		(property "Reference" "R266"
			(at 0 0 90)
			(layer "B.SilkS")
			(hide yes)
			(effects
				(font
					(size 1.27 1.27)
				)
				(justify mirror)
			)
		)
		(property "Value" ""
			(at 0 0 90)
			(layer "B.Fab")
			(effects
				(font
					(size 1.27 1.27)
				)
				(justify mirror)
			)
		)
		(duplicate_pad_numbers_are_jumpers no)
		(fp_line
			(start 0.7874 -0.4064)
			(end -0.7874 -0.4064)
			(stroke
				(width 0.1524)
				(type default)
			)
			(layer "B.SilkS")
		)
		(fp_line
			(start -0.7874 -0.4064)
			(end -0.7874 0.4064)
			(stroke
				(width 0.1524)
				(type default)
			)
			(layer "B.SilkS")
		)
		(fp_line
			(start 0.7874 0.4064)
			(end 0.7874 -0.4064)
			(stroke
				(width 0.1524)
				(type default)
			)
			(layer "B.SilkS")
		)
		(fp_line
			(start -0.7874 0.4064)
			(end 0.7874 0.4064)
			(stroke
				(width 0.1524)
				(type default)
			)
			(layer "B.SilkS")
		)
		(fp_line
			(start 0.67945 -0.305054)
			(end 0.12065 -0.305054)
			(stroke
				(width 0.1)
				(type default)
			)
			(layer "B.Fab")
		)
		(fp_line
			(start 0.12065 -0.305054)
			(end 0.12065 -0.2794)
			(stroke
				(width 0.1)
				(type default)
			)
			(layer "B.Fab")
		)
		(fp_line
			(start -0.12065 -0.3048)
			(end -0.67945 -0.3048)
			(stroke
				(width 0.1)
				(type default)
			)
			(layer "B.Fab")
		)
		(fp_line
			(start -0.67945 -0.3048)
			(end -0.67945 0.3048)
			(stroke
				(width 0.1)
				(type default)
			)
			(layer "B.Fab")
		)
		(fp_line
			(start 0.12065 -0.2794)
			(end -0.12065 -0.2794)
			(stroke
				(width 0.1)
				(type default)
			)
			(layer "B.Fab")
		)
		(fp_line
			(start -0.12065 -0.2794)
			(end -0.12065 -0.3048)
			(stroke
				(width 0.1)
				(type default)
			)
			(layer "B.Fab")
		)
		(fp_line
			(start 0.12065 0.2794)
			(end 0.12065 0.3048)
			(stroke
				(width 0.1)
				(type default)
			)
			(layer "B.Fab")
		)
		(fp_line
			(start -0.120396 0.2794)
			(end 0.12065 0.2794)
			(stroke
				(width 0.1)
				(type default)
			)
			(layer "B.Fab")
		)
		(fp_line
			(start 0.67945 0.3048)
			(end 0.67945 -0.305054)
			(stroke
				(width 0.1)
				(type default)
			)
			(layer "B.Fab")
		)
		(fp_line
			(start 0.12065 0.3048)
			(end 0.67945 0.3048)
			(stroke
				(width 0.1)
				(type default)
			)
			(layer "B.Fab")
		)
		(fp_line
			(start -0.120396 0.3048)
			(end -0.120396 0.2794)
			(stroke
				(width 0.1)
				(type default)
			)
			(layer "B.Fab")
		)
		(fp_line
			(start -0.67945 0.3048)
			(end -0.120396 0.3048)
			(stroke
				(width 0.1)
				(type default)
			)
			(layer "B.Fab")
		)
		(pad "1" smd circle
			(at 0.40005 0 270)
			(size 0 0)
			(layers "B.Cu" "B.Mask" "B.Paste")
			(net "FM_CPU1_SA0")
		)
		(pad "2" smd circle
			(at -0.40005 0 270)
			(size 0 0)
			(layers "B.Cu" "B.Mask" "B.Paste")
			(net "CPU1_SA0")
		)
	)
)
